G04*
G04 #@! TF.GenerationSoftware,Altium Limited,Altium Designer,23.7.1 (13)*
G04*
G04 Layer_Color=32896*
%FSLAX25Y25*%
%MOIN*%
G70*
G04*
G04 #@! TF.SameCoordinates,AF00DCEB-AC48-4C7C-91EA-99F42E284231*
G04*
G04*
G04 #@! TF.FilePolarity,Positive*
G04*
G01*
G75*
%ADD23C,0.00394*%
D23*
X596220Y-287728D02*
Y-283791D01*
X594252Y-285760D02*
X598189D01*
X544471Y-273819D02*
Y-269882D01*
X542503Y-271851D02*
X546440D01*
X580866Y-279460D02*
Y-275523D01*
X578897Y-277492D02*
X582834D01*
X580866Y-287334D02*
Y-283398D01*
X578897Y-285366D02*
X582834D01*
X554967Y-280755D02*
X558904D01*
X556936Y-282723D02*
Y-278786D01*
X587684Y-279992D02*
X591621D01*
X589652Y-281961D02*
Y-278024D01*
X596220Y-280248D02*
Y-276311D01*
X594252Y-278279D02*
X598189D01*
X477872Y-302356D02*
Y-298418D01*
X475904Y-300387D02*
X479841D01*
X480315Y-267717D02*
Y-263779D01*
X478346Y-265748D02*
X482283D01*
X187795Y-94488D02*
X191732D01*
X189764Y-96457D02*
Y-92520D01*
X149782Y3944D02*
X153719D01*
X151751Y1975D02*
Y5912D01*
X497244Y-254331D02*
Y-250394D01*
X495276Y-252362D02*
X499213D01*
X507677Y-262105D02*
Y-258168D01*
X505709Y-260136D02*
X509646D01*
X497638Y-261811D02*
Y-257874D01*
X495669Y-259842D02*
X499606D01*
X565945Y-263088D02*
Y-259151D01*
X563976Y-261119D02*
X567913D01*
X573327Y-263090D02*
Y-259154D01*
X571358Y-261122D02*
X575295D01*
X207480Y2756D02*
X211417D01*
X209449Y787D02*
Y4724D01*
X201870Y-2953D02*
X205807D01*
X203839Y-4921D02*
Y-984D01*
X212205Y-3150D02*
X216142D01*
X214173Y-5118D02*
Y-1181D01*
X202569Y-75000D02*
X206506D01*
X204537Y-76968D02*
Y-73032D01*
X212205Y-74803D02*
X216142D01*
X214173Y-76772D02*
Y-72835D01*
X408268Y-129528D02*
X412205D01*
X410236Y-131496D02*
Y-127559D01*
X413779Y-124409D02*
X417717D01*
X415748Y-126378D02*
Y-122441D01*
X427953Y-132677D02*
X431890D01*
X429921Y-134646D02*
Y-130709D01*
X54856Y-33563D02*
X58793D01*
X56824Y-35531D02*
Y-31594D01*
X111024Y-16142D02*
X114961D01*
X112992Y-18110D02*
Y-14173D01*
X95669Y-79134D02*
Y-75197D01*
X93701Y-77165D02*
X97638D01*
X106693Y-46199D02*
X110630D01*
X108661Y-48167D02*
Y-44230D01*
X279921Y-195276D02*
X283858D01*
X281890Y-197244D02*
Y-193307D01*
X337402Y-292913D02*
X341339D01*
X339370Y-294882D02*
Y-290945D01*
X318504Y-293701D02*
X322441D01*
X320472Y-295669D02*
Y-291732D01*
X323622Y-239764D02*
X327559D01*
X325590Y-241732D02*
Y-237795D01*
X375984Y-232972D02*
X379921D01*
X377953Y-234941D02*
Y-231004D01*
X555118Y-330315D02*
X559055D01*
X557087Y-332283D02*
Y-328346D01*
X531250Y-328837D02*
X535187D01*
X533219Y-330806D02*
Y-326869D01*
X564173Y-309842D02*
X568110D01*
X566142Y-311811D02*
Y-307874D01*
X531250Y-312272D02*
X535187D01*
X533219Y-314241D02*
Y-310304D01*
X120079Y-36220D02*
X124016D01*
X122047Y-38189D02*
Y-34252D01*
X123435Y-74575D02*
X127372D01*
X125404Y-76543D02*
Y-72606D01*
X148033Y-73041D02*
Y-69104D01*
X146064Y-71072D02*
X150001D01*
X146664Y-45718D02*
X150601D01*
X148632Y-47687D02*
Y-43750D01*
X611024Y-238583D02*
X614961D01*
X612992Y-240551D02*
Y-236614D01*
X612357Y-231102D02*
X616294D01*
X614326Y-233071D02*
Y-229134D01*
X612303Y-302756D02*
X616240D01*
X614272Y-304724D02*
Y-300787D01*
X612303Y-302756D02*
X616240D01*
X614272Y-304724D02*
Y-300787D01*
X383988Y-135039D02*
X387925D01*
X385957Y-137008D02*
Y-133071D01*
X64528Y-57942D02*
Y-54005D01*
X62559Y-55974D02*
X66496D01*
X94095Y-46850D02*
X98032D01*
X96063Y-48819D02*
Y-44882D01*
X100000Y-46457D02*
X103937D01*
X101969Y-48425D02*
Y-44488D01*
X609055Y-64961D02*
X612992D01*
X611024Y-66929D02*
Y-62992D01*
X149445Y-124213D02*
X153382D01*
X151414Y-126181D02*
Y-122244D01*
X164961Y-103543D02*
Y-99606D01*
X162992Y-101575D02*
X166929D01*
X153150Y-103543D02*
Y-99606D01*
X151181Y-101575D02*
X155118D01*
X158661Y-101958D02*
Y-98021D01*
X156693Y-99990D02*
X160630D01*
M02*
